FILE_TYPE=LIBRARY_PARTS;
primitive 'ZENER';
  pin
    'A':
      PIN_NUMBER='(1)';
      PINUSE='UNSPEC';
      NO_LOAD_CHECK='BOTH';
      NO_IO_CHECK='BOTH';
      ALLOW_CONNECT='TRUE';
    'C':
      PIN_NUMBER='(3)';
      PINUSE='UNSPEC';
      NO_LOAD_CHECK='BOTH';
      NO_IO_CHECK='BOTH';
      ALLOW_CONNECT='TRUE';
  end_pin;
  body
    NC_PINS='(2)';
    PART_NAME='ZENER';
    PHYS_DES_PREFIX='VR';
  end_body;
end_primitive;
primitive 'ZENER_SOD123','ZENER_SOD123LF';
  pin
    'A':
      PIN_NUMBER='(2)';
      PINUSE='UNSPEC';
      NO_LOAD_CHECK='BOTH';
      NO_IO_CHECK='BOTH';
      ALLOW_CONNECT='TRUE';
    'C':
      PIN_NUMBER='(1)';
      PINUSE='UNSPEC';
      NO_LOAD_CHECK='BOTH';
      NO_IO_CHECK='BOTH';
      ALLOW_CONNECT='TRUE';
  end_pin;
  body
    PART_NAME='ZENER';
    PHYS_DES_PREFIX='VR';
  end_body;
end_primitive;
primitive 'ZENER_SM','ZENER_SMLF';
  pin
    'A':
      PIN_NUMBER='(2)';
      PINUSE='UNSPEC';
      NO_LOAD_CHECK='BOTH';
      NO_IO_CHECK='BOTH';
      ALLOW_CONNECT='TRUE';
    'C':
      PIN_NUMBER='(1)';
      PINUSE='UNSPEC';
      NO_LOAD_CHECK='BOTH';
      NO_IO_CHECK='BOTH';
      ALLOW_CONNECT='TRUE';
  end_pin;
  body
    PART_NAME='ZENER';
    PHYS_DES_PREFIX='VR';
  end_body;
end_primitive;
END.
